(kicad_pcb
	(version 20260206)
	(generator "pcbnew")
	(generator_version "10.0")
	(general
		(thickness 1.6)
		(legacy_teardrops no)
	)
	(paper "A4")
	(title_block
		(title "peb — Lightning_PEB_BRD.brd")
		(comment 1 "Lightning (Wiwynn / Facebook NVMe JBOF) / footprints 313-320 of 2563")
	)
	(layers
		(0 "F.Cu" signal "TOP")
		(4 "In1.Cu" signal "L2GND")
		(6 "In2.Cu" signal "L3")
		(8 "In3.Cu" signal "L4VCC")
		(10 "In4.Cu" signal "L5VCC")
		(12 "In5.Cu" signal "L6")
		(14 "In6.Cu" signal "L7GND")
		(2 "B.Cu" signal "BOTTOM")
		(9 "F.Adhes" user "F.Adhesive")
		(11 "B.Adhes" user "B.Adhesive")
		(13 "F.Paste" user "Package Geometry/Pastemask Top")
		(15 "B.Paste" user "Package Geometry/Pastemask Bottom")
		(5 "F.SilkS" user "Ref Des/Silkscreen Top")
		(7 "B.SilkS" user "Ref Des/Silkscreen Bottom")
		(1 "F.Mask" user "Board Geometry/Soldermask Top")
		(3 "B.Mask" user "Board Geometry/Soldermask Bottom")
		(17 "Dwgs.User" user "User.Drawings")
		(19 "Cmts.User" user "User.Comments")
		(21 "Eco1.User" user "User.Eco1")
		(23 "Eco2.User" user "User.Eco2")
		(25 "Edge.Cuts" user "Board Geometry/Outline")
		(27 "Margin" user)
		(31 "F.CrtYd" user "Package Geometry/Place Bound Top")
		(29 "B.CrtYd" user "Package Geometry/Place Bound Bottom")
		(35 "F.Fab" user "Ref Des/Assembly Top")
		(33 "B.Fab" user "Ref Des/Assembly Bottom")
	)
	(footprint ""
		(layer "F.Cu")
		(at 46.355 -194.564)
		(property "Reference" "C706"
			(at 0 0 0)
			(layer "F.SilkS")
			(hide yes)
			(effects
				(font
					(size 1.27 1.27)
				)
			)
		)
		(property "Value" "SCD1U16V2KX-3GP"
			(at 1.1811 -2.7051 0)
			(unlocked yes)
			(layer "F.Fab")
			(hide yes)
			(effects
				(font
					(size 1.016 1.016)
					(thickness 0.1524)
				)
			)
		)
		(property "Device Type" "C402H22"
			(at 1.1811 -4.2291 0)
			(unlocked yes)
			(layer "F.Fab")
			(hide yes)
			(effects
				(font
					(size 1.016 1.016)
					(thickness 0.1524)
				)
			)
		)
		(duplicate_pad_numbers_are_jumpers no)
		(fp_rect
			(start -0.4318 0.9525)
			(end 0.4318 -0.9525)
			(stroke
				(width 0)
				(type default)
			)
			(fill no)
			(layer "F.CrtYd")
		)
		(fp_rect
			(start -0.4318 0.9525)
			(end 0.4318 -0.9525)
			(stroke
				(width 0)
				(type default)
			)
			(fill no)
			(layer "F.Fab")
		)
		(pad "1" smd custom
			(at 0 -0.4445)
			(size 0.1524 0.1524)
			(layers "F.Cu" "F.Mask" "F.Paste")
			(net "P3V3_STBY")
			(options
				(clearance outline)
				(anchor circle)
			)
			(primitives
				(gr_poly
					(pts
						(arc
							(start 0.3048 -0.2032)
							(mid 0.275042 -0.275042)
							(end 0.2032 -0.3048)
						)
						(arc
							(start -0.2032 -0.3048)
							(mid -0.275042 -0.275042)
							(end -0.3048 -0.2032)
						)
						(arc
							(start -0.3048 0.2032)
							(mid -0.275042 0.275042)
							(end -0.2032 0.3048)
						)
						(arc
							(start 0.2032 0.3048)
							(mid 0.275042 0.275042)
							(end 0.3048 0.2032)
						)
					)
					(width 0)
					(fill yes)
				)
			)
		)
		(pad "2" smd custom
			(at 0 0.4445)
			(size 0.1524 0.1524)
			(layers "F.Cu" "F.Mask" "F.Paste")
			(net "GND")
			(options
				(clearance outline)
				(anchor circle)
			)
			(primitives
				(gr_poly
					(pts
						(arc
							(start 0.3048 -0.2032)
							(mid 0.275042 -0.275042)
							(end 0.2032 -0.3048)
						)
						(arc
							(start -0.2032 -0.3048)
							(mid -0.275042 -0.275042)
							(end -0.3048 -0.2032)
						)
						(arc
							(start -0.3048 0.2032)
							(mid -0.275042 0.275042)
							(end -0.2032 0.3048)
						)
						(arc
							(start 0.2032 0.3048)
							(mid 0.275042 0.275042)
							(end 0.3048 0.2032)
						)
					)
					(width 0)
					(fill yes)
				)
			)
		)
	)
	(footprint ""
		(layer "F.Cu")
		(at 31.623 -49.657 -90)
		(property "Reference" "TC10"
			(at 0 0 270)
			(layer "F.SilkS")
			(hide yes)
			(effects
				(font
					(size 1.27 1.27)
				)
			)
		)
		(property "Value" "SC10U16V5KX-1-GP"
			(at -0.0762 -6.1214 270)
			(unlocked yes)
			(layer "F.Fab")
			(hide yes)
			(effects
				(font
					(size 1.016 1.016)
					(thickness 0.1524)
				)
			)
		)
		(property "Device Type" "C805H54"
			(at -0.0762 -8.1534 270)
			(unlocked yes)
			(layer "F.Fab")
			(hide yes)
			(effects
				(font
					(size 1.016 1.016)
					(thickness 0.1524)
				)
			)
		)
		(duplicate_pad_numbers_are_jumpers no)
		(fp_line
			(start 0.635 0)
			(end -0.635 0)
			(stroke
				(width 0.508)
				(type default)
			)
			(layer "F.SilkS")
		)
		(fp_rect
			(start -0.9652 1.778)
			(end 0.9652 -1.778)
			(stroke
				(width 0)
				(type default)
			)
			(fill no)
			(layer "F.CrtYd")
		)
		(fp_poly
			(pts
				(xy -0.9652 -1.778) (xy 0.9652 -1.778) (xy 0.9652 1.778) (xy -0.9652 1.778)
			)
			(stroke
				(width 0)
				(type default)
			)
			(fill no)
			(layer "F.Fab")
		)
		(pad "1" smd rect
			(at 0 -0.9652 270)
			(size 1.397 1.143)
			(layers "F.Cu" "F.Mask" "F.Paste")
			(net "P5V_USB")
		)
		(pad "2" smd rect
			(at 0 0.9652 270)
			(size 1.397 1.143)
			(layers "F.Cu" "F.Mask" "F.Paste")
			(net "GND")
		)
	)
	(footprint ""
		(layer "F.Cu")
		(at 127.0254 -208.8896 180)
		(property "Reference" "R9036"
			(at 0 0 180)
			(layer "F.SilkS")
			(hide yes)
			(effects
				(font
					(size 1.27 1.27)
				)
			)
		)
		(property "Value" "4K7R2F-GP"
			(at 0.064008 -3.993896 180)
			(unlocked yes)
			(layer "F.Fab")
			(hide yes)
			(effects
				(font
					(size 1.016 1.016)
					(thickness 0.1524)
				)
			)
		)
		(property "Device Type" "R402H16"
			(at 0.064008 -5.517896 180)
			(unlocked yes)
			(layer "F.Fab")
			(hide yes)
			(effects
				(font
					(size 1.016 1.016)
					(thickness 0.1524)
				)
			)
		)
		(duplicate_pad_numbers_are_jumpers no)
		(fp_line
			(start 0.508 -0.9398)
			(end -0.508 -0.9398)
			(stroke
				(width 0.1524)
				(type default)
			)
			(layer "F.SilkS")
		)
		(fp_line
			(start -0.508 -0.9398)
			(end -0.508 0.9398)
			(stroke
				(width 0.1524)
				(type default)
			)
			(layer "F.SilkS")
		)
		(fp_rect
			(start -0.508 0.9398)
			(end 0.508 -0.9398)
			(stroke
				(width 0)
				(type default)
			)
			(fill no)
			(layer "F.CrtYd")
		)
		(fp_rect
			(start -0.508 0.9398)
			(end 0.508 -0.9398)
			(stroke
				(width 0)
				(type default)
			)
			(fill no)
			(layer "F.Fab")
		)
		(pad "1" smd custom
			(at 0 -0.4445 180)
			(size 0.1397 0.1397)
			(layers "F.Cu" "F.Mask" "F.Paste")
			(net "SSD_PERST#7")
			(options
				(clearance outline)
				(anchor circle)
			)
			(primitives
				(gr_poly
					(pts
						(arc
							(start -0.1778 -0.2794)
							(mid -0.249642 -0.249642)
							(end -0.2794 -0.1778)
						)
						(arc
							(start -0.2794 0.1778)
							(mid -0.249642 0.249642)
							(end -0.1778 0.2794)
						)
						(arc
							(start 0.1778 0.2794)
							(mid 0.249642 0.249642)
							(end 0.2794 0.1778)
						)
						(arc
							(start 0.2794 -0.1778)
							(mid 0.249642 -0.249642)
							(end 0.1778 -0.2794)
						)
					)
					(width 0)
					(fill yes)
				)
			)
		)
		(pad "2" smd custom
			(at 0 0.4445 180)
			(size 0.1397 0.1397)
			(layers "F.Cu" "F.Mask" "F.Paste")
			(net "GND")
			(options
				(clearance outline)
				(anchor circle)
			)
			(primitives
				(gr_poly
					(pts
						(arc
							(start -0.1778 -0.2794)
							(mid -0.249642 -0.249642)
							(end -0.2794 -0.1778)
						)
						(arc
							(start -0.2794 0.1778)
							(mid -0.249642 0.249642)
							(end -0.1778 0.2794)
						)
						(arc
							(start 0.1778 0.2794)
							(mid 0.249642 0.249642)
							(end 0.2794 0.1778)
						)
						(arc
							(start 0.2794 -0.1778)
							(mid 0.249642 -0.249642)
							(end 0.1778 -0.2794)
						)
					)
					(width 0)
					(fill yes)
				)
			)
		)
	)
	(footprint ""
		(layer "F.Cu")
		(at 29.9466 -181.4322 -90)
		(property "Reference" "R503"
			(at 0 0 270)
			(layer "F.SilkS")
			(hide yes)
			(effects
				(font
					(size 1.27 1.27)
				)
			)
		)
		(property "Value" "10KR2F-2-GP"
			(at 0.064008 -3.993896 270)
			(unlocked yes)
			(layer "F.Fab")
			(hide yes)
			(effects
				(font
					(size 1.016 1.016)
					(thickness 0.1524)
				)
			)
		)
		(property "Device Type" "R402H16"
			(at 0.064008 -5.517896 270)
			(unlocked yes)
			(layer "F.Fab")
			(hide yes)
			(effects
				(font
					(size 1.016 1.016)
					(thickness 0.1524)
				)
			)
		)
		(duplicate_pad_numbers_are_jumpers no)
		(fp_line
			(start -0.508 -0.9398)
			(end -0.508 0.9398)
			(stroke
				(width 0.1524)
				(type default)
			)
			(layer "F.SilkS")
		)
		(fp_line
			(start 0.508 -0.9398)
			(end -0.508 -0.9398)
			(stroke
				(width 0.1524)
				(type default)
			)
			(layer "F.SilkS")
		)
		(fp_rect
			(start -0.508 0.9398)
			(end 0.508 -0.9398)
			(stroke
				(width 0)
				(type default)
			)
			(fill no)
			(layer "F.CrtYd")
		)
		(fp_rect
			(start -0.508 0.9398)
			(end 0.508 -0.9398)
			(stroke
				(width 0)
				(type default)
			)
			(fill no)
			(layer "F.Fab")
		)
		(pad "1" smd custom
			(at 0 -0.4445 270)
			(size 0.1397 0.1397)
			(layers "F.Cu" "F.Mask" "F.Paste")
			(net "BMC_I2C5_BUF_READY")
			(options
				(clearance outline)
				(anchor circle)
			)
			(primitives
				(gr_poly
					(pts
						(arc
							(start -0.1778 -0.2794)
							(mid -0.249642 -0.249642)
							(end -0.2794 -0.1778)
						)
						(arc
							(start -0.2794 0.1778)
							(mid -0.249642 0.249642)
							(end -0.1778 0.2794)
						)
						(arc
							(start 0.1778 0.2794)
							(mid 0.249642 0.249642)
							(end 0.2794 0.1778)
						)
						(arc
							(start 0.2794 -0.1778)
							(mid 0.249642 -0.249642)
							(end 0.1778 -0.2794)
						)
					)
					(width 0)
					(fill yes)
				)
			)
		)
		(pad "2" smd custom
			(at 0 0.4445 270)
			(size 0.1397 0.1397)
			(layers "F.Cu" "F.Mask" "F.Paste")
			(net "P3V3_STBY")
			(options
				(clearance outline)
				(anchor circle)
			)
			(primitives
				(gr_poly
					(pts
						(arc
							(start -0.1778 -0.2794)
							(mid -0.249642 -0.249642)
							(end -0.2794 -0.1778)
						)
						(arc
							(start -0.2794 0.1778)
							(mid -0.249642 0.249642)
							(end -0.1778 0.2794)
						)
						(arc
							(start 0.1778 0.2794)
							(mid 0.249642 0.249642)
							(end 0.2794 0.1778)
						)
						(arc
							(start 0.2794 -0.1778)
							(mid 0.249642 -0.249642)
							(end 0.1778 -0.2794)
						)
					)
					(width 0)
					(fill yes)
				)
			)
		)
	)
	(footprint ""
		(layer "F.Cu")
		(at 52.197 -145.415 180)
		(property "Reference" "R311"
			(at 0 0 180)
			(layer "F.SilkS")
			(hide yes)
			(effects
				(font
					(size 1.27 1.27)
				)
			)
		)
		(property "Value" "0R2J-2-GP"
			(at 0.064008 -3.993896 180)
			(unlocked yes)
			(layer "F.Fab")
			(hide yes)
			(effects
				(font
					(size 1.016 1.016)
					(thickness 0.1524)
				)
			)
		)
		(property "Device Type" "R402H16"
			(at 0.064008 -5.517896 180)
			(unlocked yes)
			(layer "F.Fab")
			(hide yes)
			(effects
				(font
					(size 1.016 1.016)
					(thickness 0.1524)
				)
			)
		)
		(duplicate_pad_numbers_are_jumpers no)
		(fp_line
			(start 0.508 -0.9398)
			(end -0.508 -0.9398)
			(stroke
				(width 0.1524)
				(type default)
			)
			(layer "F.SilkS")
		)
		(fp_line
			(start -0.508 -0.9398)
			(end -0.508 0.9398)
			(stroke
				(width 0.1524)
				(type default)
			)
			(layer "F.SilkS")
		)
		(fp_rect
			(start -0.508 0.9398)
			(end 0.508 -0.9398)
			(stroke
				(width 0)
				(type default)
			)
			(fill no)
			(layer "F.CrtYd")
		)
		(fp_rect
			(start -0.508 0.9398)
			(end 0.508 -0.9398)
			(stroke
				(width 0)
				(type default)
			)
			(fill no)
			(layer "F.Fab")
		)
		(pad "1" smd custom
			(at 0 -0.4445 180)
			(size 0.1397 0.1397)
			(layers "F.Cu" "F.Mask" "F.Paste")
			(net "BMC0_LED_DR_R_LED0")
			(options
				(clearance outline)
				(anchor circle)
			)
			(primitives
				(gr_poly
					(pts
						(arc
							(start -0.1778 -0.2794)
							(mid -0.249642 -0.249642)
							(end -0.2794 -0.1778)
						)
						(arc
							(start -0.2794 0.1778)
							(mid -0.249642 0.249642)
							(end -0.1778 0.2794)
						)
						(arc
							(start 0.1778 0.2794)
							(mid 0.249642 0.249642)
							(end 0.2794 0.1778)
						)
						(arc
							(start 0.2794 -0.1778)
							(mid 0.249642 -0.249642)
							(end 0.1778 -0.2794)
						)
					)
					(width 0)
					(fill yes)
				)
			)
		)
		(pad "2" smd custom
			(at 0 0.4445 180)
			(size 0.1397 0.1397)
			(layers "F.Cu" "F.Mask" "F.Paste")
			(net "LED_DR_LED0")
			(options
				(clearance outline)
				(anchor circle)
			)
			(primitives
				(gr_poly
					(pts
						(arc
							(start -0.1778 -0.2794)
							(mid -0.249642 -0.249642)
							(end -0.2794 -0.1778)
						)
						(arc
							(start -0.2794 0.1778)
							(mid -0.249642 0.249642)
							(end -0.1778 0.2794)
						)
						(arc
							(start 0.1778 0.2794)
							(mid 0.249642 0.249642)
							(end 0.2794 0.1778)
						)
						(arc
							(start 0.2794 -0.1778)
							(mid 0.249642 -0.249642)
							(end 0.1778 -0.2794)
						)
					)
					(width 0)
					(fill yes)
				)
			)
		)
	)
	(footprint ""
		(layer "F.Cu")
		(at 36.322 -200.533)
		(property "Reference" "C694"
			(at 0 0 0)
			(layer "F.SilkS")
			(hide yes)
			(effects
				(font
					(size 1.27 1.27)
				)
			)
		)
		(property "Value" "SCD1U16V2KX-3GP"
			(at 1.1811 -2.7051 0)
			(unlocked yes)
			(layer "F.Fab")
			(hide yes)
			(effects
				(font
					(size 1.016 1.016)
					(thickness 0.1524)
				)
			)
		)
		(property "Device Type" "C402H22"
			(at 1.1811 -4.2291 0)
			(unlocked yes)
			(layer "F.Fab")
			(hide yes)
			(effects
				(font
					(size 1.016 1.016)
					(thickness 0.1524)
				)
			)
		)
		(duplicate_pad_numbers_are_jumpers no)
		(fp_rect
			(start -0.4318 0.9525)
			(end 0.4318 -0.9525)
			(stroke
				(width 0)
				(type default)
			)
			(fill no)
			(layer "F.CrtYd")
		)
		(fp_rect
			(start -0.4318 0.9525)
			(end 0.4318 -0.9525)
			(stroke
				(width 0)
				(type default)
			)
			(fill no)
			(layer "F.Fab")
		)
		(pad "1" smd custom
			(at 0 -0.4445)
			(size 0.1524 0.1524)
			(layers "F.Cu" "F.Mask" "F.Paste")
			(net "P3V3_STBY")
			(options
				(clearance outline)
				(anchor circle)
			)
			(primitives
				(gr_poly
					(pts
						(arc
							(start 0.3048 -0.2032)
							(mid 0.275042 -0.275042)
							(end 0.2032 -0.3048)
						)
						(arc
							(start -0.2032 -0.3048)
							(mid -0.275042 -0.275042)
							(end -0.3048 -0.2032)
						)
						(arc
							(start -0.3048 0.2032)
							(mid -0.275042 0.275042)
							(end -0.2032 0.3048)
						)
						(arc
							(start 0.2032 0.3048)
							(mid 0.275042 0.275042)
							(end 0.3048 0.2032)
						)
					)
					(width 0)
					(fill yes)
				)
			)
		)
		(pad "2" smd custom
			(at 0 0.4445)
			(size 0.1524 0.1524)
			(layers "F.Cu" "F.Mask" "F.Paste")
			(net "GND")
			(options
				(clearance outline)
				(anchor circle)
			)
			(primitives
				(gr_poly
					(pts
						(arc
							(start 0.3048 -0.2032)
							(mid 0.275042 -0.275042)
							(end 0.2032 -0.3048)
						)
						(arc
							(start -0.2032 -0.3048)
							(mid -0.275042 -0.275042)
							(end -0.3048 -0.2032)
						)
						(arc
							(start -0.3048 0.2032)
							(mid -0.275042 0.275042)
							(end -0.2032 0.3048)
						)
						(arc
							(start 0.2032 0.3048)
							(mid 0.275042 0.275042)
							(end 0.3048 0.2032)
						)
					)
					(width 0)
					(fill yes)
				)
			)
		)
	)
	(footprint ""
		(layer "F.Cu")
		(at 197.808088 -212.420454 180)
		(property "Reference" "C118"
			(at 0 0 180)
			(layer "F.SilkS")
			(hide yes)
			(effects
				(font
					(size 1.27 1.27)
				)
			)
		)
		(property "Value" "SCD22U10V2KX-1GP"
			(at 1.1811 -2.7051 180)
			(unlocked yes)
			(layer "F.Fab")
			(hide yes)
			(effects
				(font
					(size 1.016 1.016)
					(thickness 0.1524)
				)
			)
		)
		(property "Device Type" "C402H22"
			(at 1.1811 -4.2291 180)
			(unlocked yes)
			(layer "F.Fab")
			(hide yes)
			(effects
				(font
					(size 1.016 1.016)
					(thickness 0.1524)
				)
			)
		)
		(duplicate_pad_numbers_are_jumpers no)
		(fp_rect
			(start -0.4318 0.9525)
			(end 0.4318 -0.9525)
			(stroke
				(width 0)
				(type default)
			)
			(fill no)
			(layer "F.CrtYd")
		)
		(fp_rect
			(start -0.4318 0.9525)
			(end 0.4318 -0.9525)
			(stroke
				(width 0)
				(type default)
			)
			(fill no)
			(layer "F.Fab")
		)
		(pad "1" smd custom
			(at 0 -0.4445 180)
			(size 0.1524 0.1524)
			(layers "F.Cu" "F.Mask" "F.Paste")
			(net "PCIE_TX_CAP_N43")
			(options
				(clearance outline)
				(anchor circle)
			)
			(primitives
				(gr_poly
					(pts
						(arc
							(start 0.3048 -0.2032)
							(mid 0.275042 -0.275042)
							(end 0.2032 -0.3048)
						)
						(arc
							(start -0.2032 -0.3048)
							(mid -0.275042 -0.275042)
							(end -0.3048 -0.2032)
						)
						(arc
							(start -0.3048 0.2032)
							(mid -0.275042 0.275042)
							(end -0.2032 0.3048)
						)
						(arc
							(start 0.2032 0.3048)
							(mid 0.275042 0.275042)
							(end 0.3048 0.2032)
						)
					)
					(width 0)
					(fill yes)
				)
			)
		)
		(pad "2" smd custom
			(at 0 0.4445 180)
			(size 0.1524 0.1524)
			(layers "F.Cu" "F.Mask" "F.Paste")
			(net "PCIE_TX_N43")
			(options
				(clearance outline)
				(anchor circle)
			)
			(primitives
				(gr_poly
					(pts
						(arc
							(start 0.3048 -0.2032)
							(mid 0.275042 -0.275042)
							(end 0.2032 -0.3048)
						)
						(arc
							(start -0.2032 -0.3048)
							(mid -0.275042 -0.275042)
							(end -0.3048 -0.2032)
						)
						(arc
							(start -0.3048 0.2032)
							(mid -0.275042 0.275042)
							(end -0.2032 0.3048)
						)
						(arc
							(start 0.2032 0.3048)
							(mid 0.275042 0.275042)
							(end 0.3048 0.2032)
						)
					)
					(width 0)
					(fill yes)
				)
			)
		)
	)
	(footprint ""
		(layer "F.Cu")
		(at 56.98998 -144.27708 -90)
		(property "Reference" "R414"
			(at 0 0 270)
			(layer "F.SilkS")
			(hide yes)
			(effects
				(font
					(size 1.27 1.27)
				)
			)
		)
		(property "Value" "10KR2F-2-GP"
			(at 0.064008 -3.993896 270)
			(unlocked yes)
			(layer "F.Fab")
			(hide yes)
			(effects
				(font
					(size 1.016 1.016)
					(thickness 0.1524)
				)
			)
		)
		(property "Device Type" "R402H16"
			(at 0.064008 -5.517896 270)
			(unlocked yes)
			(layer "F.Fab")
			(hide yes)
			(effects
				(font
					(size 1.016 1.016)
					(thickness 0.1524)
				)
			)
		)
		(duplicate_pad_numbers_are_jumpers no)
		(fp_line
			(start -0.508 -0.9398)
			(end -0.508 0.9398)
			(stroke
				(width 0.1524)
				(type default)
			)
			(layer "F.SilkS")
		)
		(fp_line
			(start 0.508 -0.9398)
			(end -0.508 -0.9398)
			(stroke
				(width 0.1524)
				(type default)
			)
			(layer "F.SilkS")
		)
		(fp_rect
			(start -0.508 0.9398)
			(end 0.508 -0.9398)
			(stroke
				(width 0)
				(type default)
			)
			(fill no)
			(layer "F.CrtYd")
		)
		(fp_rect
			(start -0.508 0.9398)
			(end 0.508 -0.9398)
			(stroke
				(width 0)
				(type default)
			)
			(fill no)
			(layer "F.Fab")
		)
		(pad "1" smd custom
			(at 0 -0.4445 270)
			(size 0.1397 0.1397)
			(layers "F.Cu" "F.Mask" "F.Paste")
			(net "BMC_I210_PERST_N")
			(options
				(clearance outline)
				(anchor circle)
			)
			(primitives
				(gr_poly
					(pts
						(arc
							(start -0.1778 -0.2794)
							(mid -0.249642 -0.249642)
							(end -0.2794 -0.1778)
						)
						(arc
							(start -0.2794 0.1778)
							(mid -0.249642 0.249642)
							(end -0.1778 0.2794)
						)
						(arc
							(start 0.1778 0.2794)
							(mid 0.249642 0.249642)
							(end 0.2794 0.1778)
						)
						(arc
							(start 0.2794 -0.1778)
							(mid 0.249642 -0.249642)
							(end 0.1778 -0.2794)
						)
					)
					(width 0)
					(fill yes)
				)
			)
		)
		(pad "2" smd custom
			(at 0 0.4445 270)
			(size 0.1397 0.1397)
			(layers "F.Cu" "F.Mask" "F.Paste")
			(net "GND")
			(options
				(clearance outline)
				(anchor circle)
			)
			(primitives
				(gr_poly
					(pts
						(arc
							(start -0.1778 -0.2794)
							(mid -0.249642 -0.249642)
							(end -0.2794 -0.1778)
						)
						(arc
							(start -0.2794 0.1778)
							(mid -0.249642 0.249642)
							(end -0.1778 0.2794)
						)
						(arc
							(start 0.1778 0.2794)
							(mid 0.249642 0.249642)
							(end 0.2794 0.1778)
						)
						(arc
							(start 0.2794 -0.1778)
							(mid 0.249642 -0.249642)
							(end 0.1778 -0.2794)
						)
					)
					(width 0)
					(fill yes)
				)
			)
		)
	)
)
